(kicad_pcb
	(version 20260206)
	(generator "pcbnew")
	(generator_version "10.0")
	(general
		(thickness 1.6)
		(legacy_teardrops no)
	)
	(paper "A4")
	(title_block
		(title "Bryce Canyon_IOM_IOC_16318-2_OCP.brd")
		(comment 1 "Bryce Canyon / footprints 376-382 of 1605")
	)
	(layers
		(0 "F.Cu" signal "TOP")
		(4 "In1.Cu" signal "L2GND")
		(6 "In2.Cu" signal "L3")
		(8 "In3.Cu" signal "L4VCC")
		(10 "In4.Cu" signal "L5VCC")
		(12 "In5.Cu" signal "L6")
		(14 "In6.Cu" signal "L7GND")
		(2 "B.Cu" signal "BOTTOM")
		(9 "F.Adhes" user "F.Adhesive")
		(11 "B.Adhes" user "B.Adhesive")
		(13 "F.Paste" user "Package Geometry/Pastemask Top")
		(15 "B.Paste" user "Package Geometry/Pastemask Bottom")
		(5 "F.SilkS" user "Ref Des/Silkscreen Top")
		(7 "B.SilkS" user "Ref Des/Silkscreen Bottom")
		(1 "F.Mask" user "Board Geometry/Soldermask Top")
		(3 "B.Mask" user "Board Geometry/Soldermask Bottom")
		(17 "Dwgs.User" user "User.Drawings")
		(19 "Cmts.User" user "User.Comments")
		(21 "Eco1.User" user "User.Eco1")
		(23 "Eco2.User" user "User.Eco2")
		(25 "Edge.Cuts" user "Board Geometry/Outline")
		(27 "Margin" user)
		(31 "F.CrtYd" user "Package Geometry/Place Bound Top")
		(29 "B.CrtYd" user "Package Geometry/Place Bound Bottom")
		(35 "F.Fab" user "Ref Des/Assembly Top")
		(33 "B.Fab" user "Ref Des/Assembly Bottom")
	)
	(footprint ""
		(layer "F.Cu")
		(at 168.6052 -110.9726 -90)
		(property "Reference" "C220"
			(at 0 0 270)
			(layer "F.SilkS")
			(hide yes)
			(effects
				(font
					(size 1.27 1.27)
				)
			)
		)
		(property "Value" "SC10U6D3V5KX-4GP"
			(at -0.0762 -6.1214 270)
			(unlocked yes)
			(layer "F.Fab")
			(hide yes)
			(effects
				(font
					(size 1.016 1.016)
					(thickness 0.1524)
				)
			)
		)
		(property "Device Type" "C805H58"
			(at -0.0762 -8.1534 270)
			(unlocked yes)
			(layer "F.Fab")
			(hide yes)
			(effects
				(font
					(size 1.016 1.016)
					(thickness 0.1524)
				)
			)
		)
		(duplicate_pad_numbers_are_jumpers no)
		(fp_line
			(start 0.635 0)
			(end -0.635 0)
			(stroke
				(width 0.508)
				(type default)
			)
			(layer "F.SilkS")
		)
		(fp_rect
			(start -0.9652 1.778)
			(end 0.9652 -1.778)
			(stroke
				(width 0)
				(type default)
			)
			(fill no)
			(layer "F.CrtYd")
		)
		(fp_poly
			(pts
				(xy -0.9652 -1.778) (xy 0.9652 -1.778) (xy 0.9652 1.778) (xy -0.9652 1.778)
			)
			(stroke
				(width 0)
				(type default)
			)
			(fill no)
			(layer "F.Fab")
		)
		(pad "1" smd rect
			(at 0 -0.9652 270)
			(size 1.397 1.143)
			(layers "F.Cu" "F.Mask" "F.Paste")
			(net "P1V8")
		)
		(pad "2" smd rect
			(at 0 0.9652 270)
			(size 1.397 1.143)
			(layers "F.Cu" "F.Mask" "F.Paste")
			(net "GND")
		)
	)
	(footprint ""
		(layer "F.Cu")
		(at 125.23089 -10.682478 -90)
		(property "Reference" "P1"
			(at 0 0 270)
			(layer "F.SilkS")
			(hide yes)
			(effects
				(font
					(size 1.27 1.27)
				)
			)
		)
		(property "Value" "0R0603-PAD-2-GP-U"
			(at 2.1209 -0.1397 270)
			(unlocked yes)
			(layer "F.Fab")
			(hide yes)
			(effects
				(font
					(size 1.016 1.016)
					(thickness 0.1524)
				)
			)
		)
		(property "Device Type" "0R0603-PAD-1-U"
			(at 2.1209 -1.6637 270)
			(unlocked yes)
			(layer "F.Fab")
			(hide yes)
			(effects
				(font
					(size 1.016 1.016)
					(thickness 0.1524)
				)
			)
		)
		(duplicate_pad_numbers_are_jumpers no)
		(fp_rect
			(start -0.5842 1.3335)
			(end 0.5842 -1.3335)
			(stroke
				(width 0)
				(type default)
			)
			(fill no)
			(layer "F.CrtYd")
		)
		(fp_rect
			(start -0.5842 1.3335)
			(end 0.5842 -1.3335)
			(stroke
				(width 0)
				(type default)
			)
			(fill no)
			(layer "F.Fab")
		)
		(pad "1" smd custom
			(at 0 -0.762 270)
			(size 0.2159 0.2159)
			(layers "F.Cu" "F.Mask" "F.Paste")
			(net "AGND_CURRENT_MON")
			(options
				(clearance outline)
				(anchor circle)
			)
			(primitives
				(gr_poly
					(pts
						(arc
							(start -0.3302 -0.5842)
							(mid -0.402042 -0.554442)
							(end -0.4318 -0.4826)
						)
						(arc
							(start -0.4318 0.4826)
							(mid -0.402042 0.554442)
							(end -0.3302 0.5842)
						)
						(arc
							(start 0.3302 0.5842)
							(mid 0.402042 0.554442)
							(end 0.4318 0.4826)
						)
						(arc
							(start 0.4318 -0.4826)
							(mid 0.402042 -0.554442)
							(end 0.3302 -0.5842)
						)
					)
					(width 0)
					(fill yes)
				)
			)
		)
		(pad "2" smd custom
			(at 0 0.762 270)
			(size 0.2159 0.2159)
			(layers "F.Cu" "F.Mask" "F.Paste")
			(net "GND")
			(options
				(clearance outline)
				(anchor circle)
			)
			(primitives
				(gr_poly
					(pts
						(arc
							(start -0.4318 0.4826)
							(mid -0.402042 0.554442)
							(end -0.3302 0.5842)
						)
						(arc
							(start 0.3302 0.5842)
							(mid 0.402042 0.554442)
							(end 0.4318 0.4826)
						)
						(arc
							(start 0.4318 -0.4826)
							(mid 0.402042 -0.554442)
							(end 0.3302 -0.5842)
						)
						(arc
							(start -0.3302 -0.5842)
							(mid -0.402042 -0.554442)
							(end -0.4318 -0.4826)
						)
					)
					(width 0)
					(fill yes)
				)
			)
		)
	)
	(footprint ""
		(layer "F.Cu")
		(at 98.552 -145.415 -90)
		(property "Reference" "R427"
			(at 0 0 270)
			(layer "F.SilkS")
			(hide yes)
			(effects
				(font
					(size 1.27 1.27)
				)
			)
		)
		(property "Value" "0R2J-2-GP"
			(at 0.064008 -3.993896 270)
			(unlocked yes)
			(layer "F.Fab")
			(hide yes)
			(effects
				(font
					(size 1.016 1.016)
					(thickness 0.1524)
				)
			)
		)
		(property "Device Type" "R402H16"
			(at 0.064008 -5.517896 270)
			(unlocked yes)
			(layer "F.Fab")
			(hide yes)
			(effects
				(font
					(size 1.016 1.016)
					(thickness 0.1524)
				)
			)
		)
		(duplicate_pad_numbers_are_jumpers no)
		(fp_line
			(start -0.508 -0.9398)
			(end -0.508 0.9398)
			(stroke
				(width 0.1524)
				(type default)
			)
			(layer "F.SilkS")
		)
		(fp_line
			(start 0.508 -0.9398)
			(end -0.508 -0.9398)
			(stroke
				(width 0.1524)
				(type default)
			)
			(layer "F.SilkS")
		)
		(fp_rect
			(start -0.508 0.9398)
			(end 0.508 -0.9398)
			(stroke
				(width 0)
				(type default)
			)
			(fill no)
			(layer "F.CrtYd")
		)
		(fp_rect
			(start -0.508 0.9398)
			(end 0.508 -0.9398)
			(stroke
				(width 0)
				(type default)
			)
			(fill no)
			(layer "F.Fab")
		)
		(pad "1" smd custom
			(at 0 -0.4445 270)
			(size 0.1397 0.1397)
			(layers "F.Cu" "F.Mask" "F.Paste")
			(net "I2C_DEBUG_SCL_L")
			(options
				(clearance outline)
				(anchor circle)
			)
			(primitives
				(gr_poly
					(pts
						(arc
							(start -0.1778 -0.2794)
							(mid -0.249642 -0.249642)
							(end -0.2794 -0.1778)
						)
						(arc
							(start -0.2794 0.1778)
							(mid -0.249642 0.249642)
							(end -0.1778 0.2794)
						)
						(arc
							(start 0.1778 0.2794)
							(mid 0.249642 0.249642)
							(end 0.2794 0.1778)
						)
						(arc
							(start 0.2794 -0.1778)
							(mid 0.249642 -0.249642)
							(end 0.1778 -0.2794)
						)
					)
					(width 0)
					(fill yes)
				)
			)
		)
		(pad "2" smd custom
			(at 0 0.4445 270)
			(size 0.1397 0.1397)
			(layers "F.Cu" "F.Mask" "F.Paste")
			(net "I2C_DEBUG_SCL_R")
			(options
				(clearance outline)
				(anchor circle)
			)
			(primitives
				(gr_poly
					(pts
						(arc
							(start -0.1778 -0.2794)
							(mid -0.249642 -0.249642)
							(end -0.2794 -0.1778)
						)
						(arc
							(start -0.2794 0.1778)
							(mid -0.249642 0.249642)
							(end -0.1778 0.2794)
						)
						(arc
							(start 0.1778 0.2794)
							(mid 0.249642 0.249642)
							(end 0.2794 0.1778)
						)
						(arc
							(start 0.2794 -0.1778)
							(mid 0.249642 -0.249642)
							(end 0.1778 -0.2794)
						)
					)
					(width 0)
					(fill yes)
				)
			)
		)
	)
	(footprint ""
		(layer "F.Cu")
		(at 196.977 -48.26 180)
		(property "Reference" "R636"
			(at 0 0 180)
			(layer "F.SilkS")
			(hide yes)
			(effects
				(font
					(size 1.27 1.27)
				)
			)
		)
		(property "Value" "4K7R2F-GP"
			(at 0.064008 -3.993896 180)
			(unlocked yes)
			(layer "F.Fab")
			(hide yes)
			(effects
				(font
					(size 1.016 1.016)
					(thickness 0.1524)
				)
			)
		)
		(property "Device Type" "R402H16"
			(at 0.064008 -5.517896 180)
			(unlocked yes)
			(layer "F.Fab")
			(hide yes)
			(effects
				(font
					(size 1.016 1.016)
					(thickness 0.1524)
				)
			)
		)
		(duplicate_pad_numbers_are_jumpers no)
		(fp_line
			(start 0.508 -0.9398)
			(end -0.508 -0.9398)
			(stroke
				(width 0.1524)
				(type default)
			)
			(layer "F.SilkS")
		)
		(fp_line
			(start -0.508 -0.9398)
			(end -0.508 0.9398)
			(stroke
				(width 0.1524)
				(type default)
			)
			(layer "F.SilkS")
		)
		(fp_rect
			(start -0.508 0.9398)
			(end 0.508 -0.9398)
			(stroke
				(width 0)
				(type default)
			)
			(fill no)
			(layer "F.CrtYd")
		)
		(fp_rect
			(start -0.508 0.9398)
			(end 0.508 -0.9398)
			(stroke
				(width 0)
				(type default)
			)
			(fill no)
			(layer "F.Fab")
		)
		(pad "1" smd custom
			(at 0 -0.4445 180)
			(size 0.1397 0.1397)
			(layers "F.Cu" "F.Mask" "F.Paste")
			(net "P1V8")
			(options
				(clearance outline)
				(anchor circle)
			)
			(primitives
				(gr_poly
					(pts
						(arc
							(start -0.1778 -0.2794)
							(mid -0.249642 -0.249642)
							(end -0.2794 -0.1778)
						)
						(arc
							(start -0.2794 0.1778)
							(mid -0.249642 0.249642)
							(end -0.1778 0.2794)
						)
						(arc
							(start 0.1778 0.2794)
							(mid 0.249642 0.249642)
							(end 0.2794 0.1778)
						)
						(arc
							(start 0.2794 -0.1778)
							(mid 0.249642 -0.249642)
							(end 0.1778 -0.2794)
						)
					)
					(width 0)
					(fill yes)
				)
			)
		)
		(pad "2" smd custom
			(at 0 0.4445 180)
			(size 0.1397 0.1397)
			(layers "F.Cu" "F.Mask" "F.Paste")
			(net "ICE0_TCK")
			(options
				(clearance outline)
				(anchor circle)
			)
			(primitives
				(gr_poly
					(pts
						(arc
							(start -0.1778 -0.2794)
							(mid -0.249642 -0.249642)
							(end -0.2794 -0.1778)
						)
						(arc
							(start -0.2794 0.1778)
							(mid -0.249642 0.249642)
							(end -0.1778 0.2794)
						)
						(arc
							(start 0.1778 0.2794)
							(mid 0.249642 0.249642)
							(end 0.2794 0.1778)
						)
						(arc
							(start 0.2794 -0.1778)
							(mid 0.249642 -0.249642)
							(end 0.1778 -0.2794)
						)
					)
					(width 0)
					(fill yes)
				)
			)
		)
	)
	(footprint ""
		(layer "F.Cu")
		(at 24.042116 -164.3507 90)
		(property "Reference" "C226"
			(at 0 0 90)
			(layer "F.SilkS")
			(hide yes)
			(effects
				(font
					(size 1.27 1.27)
				)
			)
		)
		(property "Value" "SC10U6D3V5KX-4GP"
			(at -0.0762 -6.1214 90)
			(unlocked yes)
			(layer "F.Fab")
			(hide yes)
			(effects
				(font
					(size 1.016 1.016)
					(thickness 0.1524)
				)
			)
		)
		(property "Device Type" "C805H58"
			(at -0.0762 -8.1534 90)
			(unlocked yes)
			(layer "F.Fab")
			(hide yes)
			(effects
				(font
					(size 1.016 1.016)
					(thickness 0.1524)
				)
			)
		)
		(duplicate_pad_numbers_are_jumpers no)
		(fp_line
			(start 0.635 0)
			(end -0.635 0)
			(stroke
				(width 0.508)
				(type default)
			)
			(layer "F.SilkS")
		)
		(fp_rect
			(start -0.9652 1.778)
			(end 0.9652 -1.778)
			(stroke
				(width 0)
				(type default)
			)
			(fill no)
			(layer "F.CrtYd")
		)
		(fp_poly
			(pts
				(xy -0.9652 -1.778) (xy 0.9652 -1.778) (xy 0.9652 1.778) (xy -0.9652 1.778)
			)
			(stroke
				(width 0)
				(type default)
			)
			(fill no)
			(layer "F.Fab")
		)
		(pad "1" smd rect
			(at 0 -0.9652 90)
			(size 1.397 1.143)
			(layers "F.Cu" "F.Mask" "F.Paste")
			(net "TPS74801_P1V2_STBY_OUT")
		)
		(pad "2" smd rect
			(at 0 0.9652 90)
			(size 1.397 1.143)
			(layers "F.Cu" "F.Mask" "F.Paste")
			(net "GND")
		)
	)
	(footprint ""
		(layer "F.Cu")
		(at 176.6824 -59.0296 90)
		(property "Reference" "R664"
			(at 0 0 90)
			(layer "F.SilkS")
			(hide yes)
			(effects
				(font
					(size 1.27 1.27)
				)
			)
		)
		(property "Value" "10KR2F-2-GP"
			(at 0.064008 -3.993896 90)
			(unlocked yes)
			(layer "F.Fab")
			(hide yes)
			(effects
				(font
					(size 1.016 1.016)
					(thickness 0.1524)
				)
			)
		)
		(property "Device Type" "R402H16"
			(at 0.064008 -5.517896 90)
			(unlocked yes)
			(layer "F.Fab")
			(hide yes)
			(effects
				(font
					(size 1.016 1.016)
					(thickness 0.1524)
				)
			)
		)
		(duplicate_pad_numbers_are_jumpers no)
		(fp_line
			(start 0.508 -0.9398)
			(end -0.508 -0.9398)
			(stroke
				(width 0.1524)
				(type default)
			)
			(layer "F.SilkS")
		)
		(fp_line
			(start -0.508 -0.9398)
			(end -0.508 0.9398)
			(stroke
				(width 0.1524)
				(type default)
			)
			(layer "F.SilkS")
		)
		(fp_rect
			(start -0.508 0.9398)
			(end 0.508 -0.9398)
			(stroke
				(width 0)
				(type default)
			)
			(fill no)
			(layer "F.CrtYd")
		)
		(fp_rect
			(start -0.508 0.9398)
			(end 0.508 -0.9398)
			(stroke
				(width 0)
				(type default)
			)
			(fill no)
			(layer "F.Fab")
		)
		(pad "1" smd custom
			(at 0 -0.4445 90)
			(size 0.1397 0.1397)
			(layers "F.Cu" "F.Mask" "F.Paste")
			(net "P1V8")
			(options
				(clearance outline)
				(anchor circle)
			)
			(primitives
				(gr_poly
					(pts
						(arc
							(start -0.1778 -0.2794)
							(mid -0.249642 -0.249642)
							(end -0.2794 -0.1778)
						)
						(arc
							(start -0.2794 0.1778)
							(mid -0.249642 0.249642)
							(end -0.1778 0.2794)
						)
						(arc
							(start 0.1778 0.2794)
							(mid 0.249642 0.249642)
							(end 0.2794 0.1778)
						)
						(arc
							(start 0.2794 -0.1778)
							(mid 0.249642 -0.249642)
							(end 0.1778 -0.2794)
						)
					)
					(width 0)
					(fill yes)
				)
			)
		)
		(pad "2" smd custom
			(at 0 0.4445 90)
			(size 0.1397 0.1397)
			(layers "F.Cu" "F.Mask" "F.Paste")
			(net "XM_ADDR_23")
			(options
				(clearance outline)
				(anchor circle)
			)
			(primitives
				(gr_poly
					(pts
						(arc
							(start -0.1778 -0.2794)
							(mid -0.249642 -0.249642)
							(end -0.2794 -0.1778)
						)
						(arc
							(start -0.2794 0.1778)
							(mid -0.249642 0.249642)
							(end -0.1778 0.2794)
						)
						(arc
							(start 0.1778 0.2794)
							(mid 0.249642 0.249642)
							(end 0.2794 0.1778)
						)
						(arc
							(start 0.2794 -0.1778)
							(mid 0.249642 -0.249642)
							(end 0.1778 -0.2794)
						)
					)
					(width 0)
					(fill yes)
				)
			)
		)
	)
	(footprint ""
		(layer "F.Cu")
		(at 60.9092 -121.3612 -90)
		(property "Reference" "SKT2"
			(at 0 0 270)
			(layer "F.SilkS")
			(hide yes)
			(effects
				(font
					(size 1.27 1.27)
				)
			)
		)
		(property "Value" "SKT-SPI16P-GP-U"
			(at -8.9916 4.641596 270)
			(unlocked yes)
			(layer "F.Fab")
			(hide yes)
			(effects
				(font
					(size 1.016 1.016)
					(thickness 0.1524)
				)
			)
		)
		(property "Device Type" "SKT-SOIC16-153139H258"
			(at -8.9916 3.117596 270)
			(unlocked yes)
			(layer "F.Fab")
			(hide yes)
			(effects
				(font
					(size 1.016 1.016)
					(thickness 0.1524)
				)
			)
		)
		(duplicate_pad_numbers_are_jumpers no)
		(fp_line
			(start -7.8994 6.4008)
			(end 7.8994 6.4008)
			(stroke
				(width 0.1524)
				(type default)
			)
			(layer "F.SilkS")
		)
		(fp_line
			(start 7.8994 6.4008)
			(end 7.8994 -6.4008)
			(stroke
				(width 0.1524)
				(type default)
			)
			(layer "F.SilkS")
		)
		(fp_line
			(start 6.7183 0.0762)
			(end 7.8994 1.2573)
			(stroke
				(width 0.1524)
				(type default)
			)
			(layer "F.SilkS")
		)
		(fp_line
			(start 7.8867 -1.0922)
			(end 6.7183 0.0762)
			(stroke
				(width 0.1524)
				(type default)
			)
			(layer "F.SilkS")
		)
		(fp_line
			(start 7.7216 -6.223)
			(end 7.7216 -3.6576)
			(stroke
				(width 0.508)
				(type default)
			)
			(layer "F.SilkS")
		)
		(fp_line
			(start -7.8994 -6.4008)
			(end -7.8994 6.4008)
			(stroke
				(width 0.1524)
				(type default)
			)
			(layer "F.SilkS")
		)
		(fp_line
			(start 7.8994 -6.4008)
			(end -7.8994 -6.4008)
			(stroke
				(width 0.1524)
				(type default)
			)
			(layer "F.SilkS")
		)
		(fp_poly
			(pts
				(xy -4.699 -3.855466) (xy -4.699 3.855466) (xy 4.699 3.855466) (xy 4.699 -3.855466)
			)
			(stroke
				(width 0)
				(type default)
			)
			(fill yes)
			(layer "F.SilkS")
		)
		(fp_rect
			(start -8.1534 11.6078)
			(end 8.1534 6.4008)
			(stroke
				(width 0)
				(type default)
			)
			(fill no)
			(layer "F.CrtYd")
		)
		(fp_rect
			(start -8.1534 -6.4008)
			(end 8.1534 -12.5222)
			(stroke
				(width 0)
				(type default)
			)
			(fill no)
			(layer "F.CrtYd")
		)
		(fp_poly
			(pts
				(xy -8.1534 6.4008) (xy -8.1534 -6.4008) (xy -6.2484 -6.4008) (xy -6.2484 -2.6416) (xy -7.6454 -2.6416)
				(xy -7.6454 2.6416) (xy -6.2484 2.6416) (xy -6.2484 6.4008)
			)
			(stroke
				(width 0)
				(type default)
			)
			(fill no)
			(layer "F.CrtYd")
		)
		(fp_poly
			(pts
				(xy 6.2484 -6.4008) (xy 8.1534 -6.4008) (xy 8.1534 6.4008) (xy 6.2484 6.4008) (xy 6.2484 2.6416)
				(xy 7.6454 2.6416) (xy 7.6454 -2.6416) (xy 6.2484 -2.6416)
			)
			(stroke
				(width 0)
				(type default)
			)
			(fill no)
			(layer "F.CrtYd")
		)
		(fp_poly
			(pts
				(xy 6.2484 -6.4008) (xy -6.2484 -6.4008) (xy -6.2484 -2.6416) (xy -7.6454 -2.6416) (xy -7.6454 2.6416)
				(xy -6.2484 2.6416) (xy -6.2484 6.4008) (xy 6.2484 6.4008) (xy 6.2484 2.6416) (xy 7.6454 2.6416)
				(xy 7.6454 -2.6416) (xy 6.2484 -2.6416)
			)
			(stroke
				(width 0)
				(type default)
			)
			(fill no)
			(layer "F.CrtYd")
		)
		(fp_rect
			(start -8.1534 11.6078)
			(end 8.1534 -12.5222)
			(stroke
				(width 0)
				(type default)
			)
			(fill no)
			(layer "F.Fab")
		)
		(pad "1" smd rect
			(at 4.445 -4.896866 270)
			(size 0.508 1.6764)
			(layers "F.Cu" "F.Mask" "F.Paste")
			(net "PU_IBMC_BT_HOLD_N")
		)
		(pad "2" smd rect
			(at 3.175 -4.896866 270)
			(size 0.508 1.6764)
			(layers "F.Cu" "F.Mask" "F.Paste")
			(net "P3V3_STBY")
		)
		(pad "3" smd rect
			(at 1.905 -4.896866 270)
			(size 0.508 1.6764)
			(layers "F.Cu" "F.Mask" "F.Paste")
			(net "FLA1_SPI_RST")
		)
		(pad "4" smd rect
			(at 0.635 -4.896866 270)
			(size 0.508 1.6764)
			(layers "F.Cu" "F.Mask" "F.Paste")
			(net "Net_345")
		)
		(pad "5" smd rect
			(at -0.635 -4.896866 270)
			(size 0.508 1.6764)
			(layers "F.Cu" "F.Mask" "F.Paste")
			(net "Net_344")
		)
		(pad "6" smd rect
			(at -1.905 -4.896866 270)
			(size 0.508 1.6764)
			(layers "F.Cu" "F.Mask" "F.Paste")
			(net "Net_343")
		)
		(pad "7" smd rect
			(at -3.175 -4.896866 270)
			(size 0.508 1.6764)
			(layers "F.Cu" "F.Mask" "F.Paste")
			(net "FLA_CS_1_R")
		)
		(pad "8" smd rect
			(at -4.445 -4.896866 270)
			(size 0.508 1.6764)
			(layers "F.Cu" "F.Mask" "F.Paste")
			(net "BMC_SPI_MISO_R")
		)
		(pad "9" smd rect
			(at -4.445 4.896866 270)
			(size 0.508 1.6764)
			(layers "F.Cu" "F.Mask" "F.Paste")
			(net "FLA1_WP_N")
		)
		(pad "10" smd rect
			(at -3.175 4.896866 270)
			(size 0.508 1.6764)
			(layers "F.Cu" "F.Mask" "F.Paste")
			(net "GND")
		)
		(pad "11" smd rect
			(at -1.905 4.896866 270)
			(size 0.508 1.6764)
			(layers "F.Cu" "F.Mask" "F.Paste")
			(net "Net_349")
		)
		(pad "12" smd rect
			(at -0.635 4.896866 270)
			(size 0.508 1.6764)
			(layers "F.Cu" "F.Mask" "F.Paste")
			(net "Net_348")
		)
		(pad "13" smd rect
			(at 0.635 4.896866 270)
			(size 0.508 1.6764)
			(layers "F.Cu" "F.Mask" "F.Paste")
			(net "Net_347")
		)
		(pad "14" smd rect
			(at 1.905 4.896866 270)
			(size 0.508 1.6764)
			(layers "F.Cu" "F.Mask" "F.Paste")
			(net "Net_346")
		)
		(pad "15" smd rect
			(at 3.175 4.896866 270)
			(size 0.508 1.6764)
			(layers "F.Cu" "F.Mask" "F.Paste")
			(net "BMC_SPI_MOSI_R")
		)
		(pad "16" smd rect
			(at 4.445 4.896866 270)
			(size 0.508 1.6764)
			(layers "F.Cu" "F.Mask" "F.Paste")
			(net "BMC_SPI_CLK_R")
		)
	)
)
